# BASEBOARD_FAB2 (Tioga Pass) — schematic netlist excerpt (pin names and nets, part order shuffled) for the footprints in the layout excerpt that follows; sources: Cadence DE-HDL packaged netlist, KiCad conversion of Wiwynn_Tioga_Pass_MB.brd

CF7  SC22P50V2JN-4GP  5%  pkg SMD-BCG  page 206 : \1\ = VR_PVCCIN_CPU1_AIREF1 ; \2\ = ISENSE_PVCCIN_CPU1_PH1_IMON
R9F63  RES  0.0 5% EMPTY  pkg 0402  page 181 : A = SPA_MID_DBG_RX ; B = SPA_MID_DBG_RX_R

(kicad_pcb
	(version 20260206)
	(generator "pcbnew")
	(generator_version "10.0")
	(general
		(thickness 1.6)
		(legacy_teardrops no)
	)
	(paper "A4")
	(title_block
		(title "Wiwynn_Tioga_Pass_MB.brd")
		(comment 1 "Tioga Pass / footprints 1118-1119 of 4770")
	)
	(layers
		(0 "F.Cu" signal "TOP")
		(4 "In1.Cu" signal "L2GND")
		(6 "In2.Cu" signal "L3")
		(8 "In3.Cu" signal "L4GND")
		(10 "In4.Cu" signal "L5")
		(12 "In5.Cu" signal "L6GND")
		(14 "In6.Cu" signal "L7VCC")
		(16 "In7.Cu" signal "L8VCC")
		(18 "In8.Cu" signal "L9GND")
		(20 "In9.Cu" signal "L10")
		(22 "In10.Cu" signal "L11GND")
		(24 "In11.Cu" signal "L12")
		(26 "In12.Cu" signal "L13GND")
		(2 "B.Cu" signal "BOTTOM")
		(9 "F.Adhes" user "F.Adhesive")
		(11 "B.Adhes" user "B.Adhesive")
		(13 "F.Paste" user "Package Geometry/Pastemask Top")
		(15 "B.Paste" user "Package Geometry/Pastemask Bottom")
		(5 "F.SilkS" user "Ref Des/Silkscreen Top")
		(7 "B.SilkS" user "Ref Des/Silkscreen Bottom")
		(1 "F.Mask" user "Board Geometry/Soldermask Top")
		(3 "B.Mask" user "Board Geometry/Soldermask Bottom")
		(17 "Dwgs.User" user "User.Drawings")
		(19 "Cmts.User" user "User.Comments")
		(21 "Eco1.User" user "User.Eco1")
		(23 "Eco2.User" user "User.Eco2")
		(25 "Edge.Cuts" user "Board Geometry/Outline")
		(27 "Margin" user)
		(31 "F.CrtYd" user "Package Geometry/Place Bound Top")
		(29 "B.CrtYd" user "Package Geometry/Place Bound Bottom")
		(35 "F.Fab" user "Ref Des/Assembly Top")
		(33 "B.Fab" user "Ref Des/Assembly Bottom")
	)
	(footprint ""
		(layer "F.Cu")
		(at 487.970576 -28.408376 180)
		(property "Reference" "R9F63"
			(at 0 0 180)
			(layer "F.SilkS")
			(hide yes)
			(effects
				(font
					(size 1.27 1.27)
				)
			)
		)
		(property "Value" ""
			(at 0 0 180)
			(layer "F.Fab")
			(effects
				(font
					(size 1.27 1.27)
				)
			)
		)
		(duplicate_pad_numbers_are_jumpers no)
		(fp_poly
			(pts
				(xy -0.2794 -0.1016) (xy 0.2794 -0.1016) (xy 0.2794 0.9906) (xy -0.2794 0.9906)
			)
			(stroke
				(width 0)
				(type default)
			)
			(fill no)
			(layer "F.CrtYd")
		)
		(fp_line
			(start 0.2794 0.9906)
			(end 0.2794 -0.1016)
			(stroke
				(width 0.1)
				(type default)
			)
			(layer "F.Fab")
		)
		(fp_line
			(start 0.2794 -0.1016)
			(end -0.2794 -0.1016)
			(stroke
				(width 0.1)
				(type default)
			)
			(layer "F.Fab")
		)
		(fp_line
			(start -0.2794 0.9906)
			(end 0.2794 0.9906)
			(stroke
				(width 0.1)
				(type default)
			)
			(layer "F.Fab")
		)
		(fp_line
			(start -0.2794 -0.1016)
			(end -0.2794 0.9906)
			(stroke
				(width 0.1)
				(type default)
			)
			(layer "F.Fab")
		)
		(pad "1" smd rect
			(at 0 0 180)
			(size 0.508 0.508)
			(layers "F.Cu" "F.Mask" "F.Paste")
			(net "SPA_MID_DBG_RX")
		)
		(pad "2" smd rect
			(at 0 0.889 180)
			(size 0.508 0.508)
			(layers "F.Cu" "F.Mask" "F.Paste")
			(net "SPA_MID_DBG_RX_R")
		)
		(zone
			(layer "F.Cu")
			(hatch none 0.5)
			(connect_pads
				(clearance 0)
			)
			(min_thickness 0.25)
			(keepout
				(tracks not_allowed)
				(vias allowed)
				(pads allowed)
				(copperpour not_allowed)
				(footprints allowed)
			)
			(placement
				(enabled no)
				(sheetname "")
			)
			(fill
				(thermal_gap 0.5)
				(thermal_bridge_width 0.5)
				(island_removal_mode 0)
			)
			(polygon
				(pts
					(xy 488.224576 -29.043376) (xy 487.716576 -29.043376) (xy 487.716576 -28.662376) (xy 488.224576 -28.662376)
				)
			)
		)
		(zone
			(layer "F.Cu")
			(hatch none 0.5)
			(connect_pads
				(clearance 0)
			)
			(min_thickness 0.25)
			(keepout
				(tracks allowed)
				(vias not_allowed)
				(pads allowed)
				(copperpour not_allowed)
				(footprints allowed)
			)
			(placement
				(enabled no)
				(sheetname "")
			)
			(fill
				(thermal_gap 0.5)
				(thermal_bridge_width 0.5)
				(island_removal_mode 0)
			)
			(polygon
				(pts
					(xy 488.224576 -28.662376) (xy 487.716576 -28.662376) (xy 487.716576 -29.043376) (xy 488.224576 -29.043376)
				)
			)
		)
	)
	(footprint ""
		(layer "F.Cu")
		(at 24.123142 -86.380066 180)
		(property "Reference" "CF7"
			(at 0 0 180)
			(layer "F.SilkS")
			(hide yes)
			(effects
				(font
					(size 1.27 1.27)
				)
			)
		)
		(property "Value" "*"
			(at 1.1811 -2.8194 180)
			(unlocked yes)
			(layer "F.Fab")
			(hide yes)
			(effects
				(font
					(size 1.27 1.016)
					(thickness 0.1524)
				)
			)
		)
		(property "Device Type" "SC22P50V2JN-4GP_SMD-BCG-SC22P5A"
			(at 1.1811 -4.3434 180)
			(unlocked yes)
			(layer "F.Fab")
			(hide yes)
			(effects
				(font
					(size 1.27 1.016)
					(thickness 0.1524)
				)
			)
		)
		(duplicate_pad_numbers_are_jumpers no)
		(fp_rect
			(start -0.4318 0.9525)
			(end 0.4318 -0.9525)
			(stroke
				(width 0)
				(type default)
			)
			(fill no)
			(layer "F.CrtYd")
		)
		(fp_rect
			(start -0.4318 0.9525)
			(end 0.4318 -0.9525)
			(stroke
				(width 0)
				(type default)
			)
			(fill no)
			(layer "F.Fab")
		)
		(pad "1" smd custom
			(at 0 -0.4445 180)
			(size 0.1524 0.1524)
			(layers "F.Cu" "F.Mask" "F.Paste")
			(net "VR_PVCCIN_CPU1_AIREF1")
			(options
				(clearance outline)
				(anchor circle)
			)
			(primitives
				(gr_poly
					(pts
						(arc
							(start 0.3048 -0.2032)
							(mid 0.275042 -0.275042)
							(end 0.2032 -0.3048)
						)
						(arc
							(start -0.2032 -0.3048)
							(mid -0.275042 -0.275042)
							(end -0.3048 -0.2032)
						)
						(arc
							(start -0.3048 0.2032)
							(mid -0.275042 0.275042)
							(end -0.2032 0.3048)
						)
						(arc
							(start 0.2032 0.3048)
							(mid 0.275042 0.275042)
							(end 0.3048 0.2032)
						)
					)
					(width 0)
					(fill yes)
				)
			)
		)
		(pad "2" smd custom
			(at 0 0.4445 180)
			(size 0.1524 0.1524)
			(layers "F.Cu" "F.Mask" "F.Paste")
			(net "ISENSE_PVCCIN_CPU1_PH1_IMON")
			(options
				(clearance outline)
				(anchor circle)
			)
			(primitives
				(gr_poly
					(pts
						(arc
							(start 0.3048 -0.2032)
							(mid 0.275042 -0.275042)
							(end 0.2032 -0.3048)
						)
						(arc
							(start -0.2032 -0.3048)
							(mid -0.275042 -0.275042)
							(end -0.3048 -0.2032)
						)
						(arc
							(start -0.3048 0.2032)
							(mid -0.275042 0.275042)
							(end -0.2032 0.3048)
						)
						(arc
							(start 0.2032 0.3048)
							(mid 0.275042 0.275042)
							(end 0.3048 0.2032)
						)
					)
					(width 0)
					(fill yes)
				)
			)
		)
	)
)
